(kicad_pcb
	(version 20260206)
	(generator "pcbnew")
	(generator_version "10.0")
	(general
		(thickness 1.6)
		(legacy_teardrops no)
	)
	(paper "A4")
	(title_block
		(title "Bryce Canyon_F.DPB_16315-1-OCP.brd")
		(comment 1 "Bryce Canyon / footprints 908-915 of 2223")
	)
	(layers
		(0 "F.Cu" signal "TOP")
		(4 "In1.Cu" signal "L2GND")
		(6 "In2.Cu" signal "L3")
		(8 "In3.Cu" signal "L4GND")
		(10 "In4.Cu" signal "L5")
		(12 "In5.Cu" signal "L6VCC")
		(14 "In6.Cu" signal "L7VCC")
		(16 "In7.Cu" signal "L8")
		(18 "In8.Cu" signal "L9GND")
		(20 "In9.Cu" signal "L10")
		(22 "In10.Cu" signal "L11GND")
		(2 "B.Cu" signal "BOTTOM")
		(9 "F.Adhes" user "F.Adhesive")
		(11 "B.Adhes" user "B.Adhesive")
		(13 "F.Paste" user "Package Geometry/Pastemask Top")
		(15 "B.Paste" user "Package Geometry/Pastemask Bottom")
		(5 "F.SilkS" user "Ref Des/Silkscreen Top")
		(7 "B.SilkS" user "Ref Des/Silkscreen Bottom")
		(1 "F.Mask" user "Board Geometry/Soldermask Top")
		(3 "B.Mask" user "Board Geometry/Soldermask Bottom")
		(17 "Dwgs.User" user "User.Drawings")
		(19 "Cmts.User" user "User.Comments")
		(21 "Eco1.User" user "User.Eco1")
		(23 "Eco2.User" user "User.Eco2")
		(25 "Edge.Cuts" user "Board Geometry/Outline")
		(27 "Margin" user)
		(31 "F.CrtYd" user "Package Geometry/Place Bound Top")
		(29 "B.CrtYd" user "Package Geometry/Place Bound Bottom")
		(35 "F.Fab" user "Ref Des/Assembly Top")
		(33 "B.Fab" user "Ref Des/Assembly Bottom")
	)
	(footprint ""
		(layer "F.Cu")
		(at 223.182942 -205.639162 180)
		(property "Reference" "R412"
			(at 0 0 180)
			(layer "F.SilkS")
			(hide yes)
			(effects
				(font
					(size 1.27 1.27)
				)
			)
		)
		(property "Value" "1KR2F-3-GP"
			(at 0.064008 -3.993896 180)
			(unlocked yes)
			(layer "F.Fab")
			(hide yes)
			(effects
				(font
					(size 1.016 1.016)
					(thickness 0.1524)
				)
			)
		)
		(property "Device Type" "R402H16"
			(at 0.064008 -5.517896 180)
			(unlocked yes)
			(layer "F.Fab")
			(hide yes)
			(effects
				(font
					(size 1.016 1.016)
					(thickness 0.1524)
				)
			)
		)
		(duplicate_pad_numbers_are_jumpers no)
		(fp_line
			(start 0.508 -0.9398)
			(end -0.508 -0.9398)
			(stroke
				(width 0.1524)
				(type default)
			)
			(layer "F.SilkS")
		)
		(fp_line
			(start -0.508 -0.9398)
			(end -0.508 0.9398)
			(stroke
				(width 0.1524)
				(type default)
			)
			(layer "F.SilkS")
		)
		(fp_rect
			(start -0.508 0.9398)
			(end 0.508 -0.9398)
			(stroke
				(width 0)
				(type default)
			)
			(fill no)
			(layer "F.CrtYd")
		)
		(fp_rect
			(start -0.508 0.9398)
			(end 0.508 -0.9398)
			(stroke
				(width 0)
				(type default)
			)
			(fill no)
			(layer "F.Fab")
		)
		(pad "1" smd custom
			(at 0 -0.4445 180)
			(size 0.1397 0.1397)
			(layers "F.Cu" "F.Mask" "F.Paste")
			(net "P3V3_STBY_A")
			(options
				(clearance outline)
				(anchor circle)
			)
			(primitives
				(gr_poly
					(pts
						(arc
							(start -0.1778 -0.2794)
							(mid -0.249642 -0.249642)
							(end -0.2794 -0.1778)
						)
						(arc
							(start -0.2794 0.1778)
							(mid -0.249642 0.249642)
							(end -0.1778 0.2794)
						)
						(arc
							(start 0.1778 0.2794)
							(mid 0.249642 0.249642)
							(end 0.2794 0.1778)
						)
						(arc
							(start 0.2794 -0.1778)
							(mid 0.249642 -0.249642)
							(end 0.1778 -0.2794)
						)
					)
					(width 0)
					(fill yes)
				)
			)
		)
		(pad "2" smd custom
			(at 0 0.4445 180)
			(size 0.1397 0.1397)
			(layers "F.Cu" "F.Mask" "F.Paste")
			(net "I2C_SCC_A_SCL_BUF")
			(options
				(clearance outline)
				(anchor circle)
			)
			(primitives
				(gr_poly
					(pts
						(arc
							(start -0.1778 -0.2794)
							(mid -0.249642 -0.249642)
							(end -0.2794 -0.1778)
						)
						(arc
							(start -0.2794 0.1778)
							(mid -0.249642 0.249642)
							(end -0.1778 0.2794)
						)
						(arc
							(start 0.1778 0.2794)
							(mid 0.249642 0.249642)
							(end 0.2794 0.1778)
						)
						(arc
							(start 0.2794 -0.1778)
							(mid 0.249642 -0.249642)
							(end 0.1778 -0.2794)
						)
					)
					(width 0)
					(fill yes)
				)
			)
		)
	)
	(footprint ""
		(layer "F.Cu")
		(at 177.8 -61.000894 -90)
		(property "Reference" "C418"
			(at 0 0 270)
			(layer "F.SilkS")
			(hide yes)
			(effects
				(font
					(size 1.27 1.27)
				)
			)
		)
		(property "Value" "SC10U16V6KX-2GP"
			(at -0.0762 -5.1308 270)
			(unlocked yes)
			(layer "F.Fab")
			(hide yes)
			(effects
				(font
					(size 1.016 1.016)
					(thickness 0.1524)
				)
			)
		)
		(property "Device Type" "C1206H71"
			(at -0.127 -6.6548 270)
			(unlocked yes)
			(layer "F.Fab")
			(hide yes)
			(effects
				(font
					(size 1.016 1.016)
					(thickness 0.1524)
				)
			)
		)
		(duplicate_pad_numbers_are_jumpers no)
		(fp_line
			(start -1.016 2.2352)
			(end -1.016 0.8382)
			(stroke
				(width 0.1524)
				(type default)
			)
			(layer "F.SilkS")
		)
		(fp_line
			(start 1.016 2.2352)
			(end -1.016 2.2352)
			(stroke
				(width 0.1524)
				(type default)
			)
			(layer "F.SilkS")
		)
		(fp_line
			(start 1.016 0.8382)
			(end 1.016 2.2352)
			(stroke
				(width 0.1524)
				(type default)
			)
			(layer "F.SilkS")
		)
		(fp_line
			(start -1.016 -0.8382)
			(end -1.016 -2.2352)
			(stroke
				(width 0.1524)
				(type default)
			)
			(layer "F.SilkS")
		)
		(fp_line
			(start -1.016 -2.2352)
			(end 1.016 -2.2352)
			(stroke
				(width 0.1524)
				(type default)
			)
			(layer "F.SilkS")
		)
		(fp_line
			(start 1.016 -2.2352)
			(end 1.016 -0.8382)
			(stroke
				(width 0.1524)
				(type default)
			)
			(layer "F.SilkS")
		)
		(fp_rect
			(start -1.0922 2.3114)
			(end 1.0922 -2.3114)
			(stroke
				(width 0)
				(type default)
			)
			(fill no)
			(layer "F.CrtYd")
		)
		(fp_poly
			(pts
				(xy 1.0922 -2.3114) (xy 1.0922 2.3114) (xy -1.0922 2.3114) (xy -1.0922 -2.3114)
			)
			(stroke
				(width 0)
				(type default)
			)
			(fill no)
			(layer "F.Fab")
		)
		(pad "1" smd rect
			(at 0 -1.397 270)
			(size 1.651 1.27)
			(layers "F.Cu" "F.Mask" "F.Paste")
			(net "P5V_HDD29")
		)
		(pad "2" smd rect
			(at 0 1.397 270)
			(size 1.651 1.27)
			(layers "F.Cu" "F.Mask" "F.Paste")
			(net "GND")
		)
	)
	(footprint ""
		(layer "F.Cu")
		(at 241.935 -231.14 180)
		(property "Reference" "R88"
			(at 0 0 180)
			(layer "F.SilkS")
			(hide yes)
			(effects
				(font
					(size 1.27 1.27)
				)
			)
		)
		(property "Value" "4K7R2F-GP"
			(at 0.064008 -3.993896 180)
			(unlocked yes)
			(layer "F.Fab")
			(hide yes)
			(effects
				(font
					(size 1.016 1.016)
					(thickness 0.1524)
				)
			)
		)
		(property "Device Type" "R402H16"
			(at 0.064008 -5.517896 180)
			(unlocked yes)
			(layer "F.Fab")
			(hide yes)
			(effects
				(font
					(size 1.016 1.016)
					(thickness 0.1524)
				)
			)
		)
		(duplicate_pad_numbers_are_jumpers no)
		(fp_line
			(start 0.508 -0.9398)
			(end -0.508 -0.9398)
			(stroke
				(width 0.1524)
				(type default)
			)
			(layer "F.SilkS")
		)
		(fp_line
			(start -0.508 -0.9398)
			(end -0.508 0.9398)
			(stroke
				(width 0.1524)
				(type default)
			)
			(layer "F.SilkS")
		)
		(fp_rect
			(start -0.508 0.9398)
			(end 0.508 -0.9398)
			(stroke
				(width 0)
				(type default)
			)
			(fill no)
			(layer "F.CrtYd")
		)
		(fp_rect
			(start -0.508 0.9398)
			(end 0.508 -0.9398)
			(stroke
				(width 0)
				(type default)
			)
			(fill no)
			(layer "F.Fab")
		)
		(pad "1" smd custom
			(at 0 -0.4445 180)
			(size 0.1397 0.1397)
			(layers "F.Cu" "F.Mask" "F.Paste")
			(net "P3V3_STBY_A")
			(options
				(clearance outline)
				(anchor circle)
			)
			(primitives
				(gr_poly
					(pts
						(arc
							(start -0.1778 -0.2794)
							(mid -0.249642 -0.249642)
							(end -0.2794 -0.1778)
						)
						(arc
							(start -0.2794 0.1778)
							(mid -0.249642 0.249642)
							(end -0.1778 0.2794)
						)
						(arc
							(start 0.1778 0.2794)
							(mid 0.249642 0.249642)
							(end 0.2794 0.1778)
						)
						(arc
							(start 0.2794 -0.1778)
							(mid 0.249642 -0.249642)
							(end 0.1778 -0.2794)
						)
					)
					(width 0)
					(fill yes)
				)
			)
		)
		(pad "2" smd custom
			(at 0 0.4445 180)
			(size 0.1397 0.1397)
			(layers "F.Cu" "F.Mask" "F.Paste")
			(net "IO_EXP2_INT_N")
			(options
				(clearance outline)
				(anchor circle)
			)
			(primitives
				(gr_poly
					(pts
						(arc
							(start -0.1778 -0.2794)
							(mid -0.249642 -0.249642)
							(end -0.2794 -0.1778)
						)
						(arc
							(start -0.2794 0.1778)
							(mid -0.249642 0.249642)
							(end -0.1778 0.2794)
						)
						(arc
							(start 0.1778 0.2794)
							(mid 0.249642 0.249642)
							(end 0.2794 0.1778)
						)
						(arc
							(start 0.2794 -0.1778)
							(mid 0.249642 -0.249642)
							(end 0.1778 -0.2794)
						)
					)
					(width 0)
					(fill yes)
				)
			)
		)
	)
	(footprint ""
		(layer "F.Cu")
		(at 83.149948 -61.000894 -90)
		(property "Reference" "C379"
			(at 0 0 270)
			(layer "F.SilkS")
			(hide yes)
			(effects
				(font
					(size 1.27 1.27)
				)
			)
		)
		(property "Value" "SC10U16V6KX-2GP"
			(at -0.0762 -5.1308 270)
			(unlocked yes)
			(layer "F.Fab")
			(hide yes)
			(effects
				(font
					(size 1.016 1.016)
					(thickness 0.1524)
				)
			)
		)
		(property "Device Type" "C1206H71"
			(at -0.127 -6.6548 270)
			(unlocked yes)
			(layer "F.Fab")
			(hide yes)
			(effects
				(font
					(size 1.016 1.016)
					(thickness 0.1524)
				)
			)
		)
		(duplicate_pad_numbers_are_jumpers no)
		(fp_line
			(start -1.016 2.2352)
			(end -1.016 0.8382)
			(stroke
				(width 0.1524)
				(type default)
			)
			(layer "F.SilkS")
		)
		(fp_line
			(start 1.016 2.2352)
			(end -1.016 2.2352)
			(stroke
				(width 0.1524)
				(type default)
			)
			(layer "F.SilkS")
		)
		(fp_line
			(start 1.016 0.8382)
			(end 1.016 2.2352)
			(stroke
				(width 0.1524)
				(type default)
			)
			(layer "F.SilkS")
		)
		(fp_line
			(start -1.016 -0.8382)
			(end -1.016 -2.2352)
			(stroke
				(width 0.1524)
				(type default)
			)
			(layer "F.SilkS")
		)
		(fp_line
			(start -1.016 -2.2352)
			(end 1.016 -2.2352)
			(stroke
				(width 0.1524)
				(type default)
			)
			(layer "F.SilkS")
		)
		(fp_line
			(start 1.016 -2.2352)
			(end 1.016 -0.8382)
			(stroke
				(width 0.1524)
				(type default)
			)
			(layer "F.SilkS")
		)
		(fp_rect
			(start -1.0922 2.3114)
			(end 1.0922 -2.3114)
			(stroke
				(width 0)
				(type default)
			)
			(fill no)
			(layer "F.CrtYd")
		)
		(fp_poly
			(pts
				(xy 1.0922 -2.3114) (xy 1.0922 2.3114) (xy -1.0922 2.3114) (xy -1.0922 -2.3114)
			)
			(stroke
				(width 0)
				(type default)
			)
			(fill no)
			(layer "F.Fab")
		)
		(pad "1" smd rect
			(at 0 -1.397 270)
			(size 1.651 1.27)
			(layers "F.Cu" "F.Mask" "F.Paste")
			(net "P5V_HDD26")
		)
		(pad "2" smd rect
			(at 0 1.397 270)
			(size 1.651 1.27)
			(layers "F.Cu" "F.Mask" "F.Paste")
			(net "GND")
		)
	)
	(footprint ""
		(layer "F.Cu")
		(at 95.563436 -158.660592 90)
		(property "Reference" "C221"
			(at 0 0 90)
			(layer "F.SilkS")
			(hide yes)
			(effects
				(font
					(size 1.27 1.27)
				)
			)
		)
		(property "Value" "SCD01U16V1KX-GP"
			(at -2.8321 -1.7399 90)
			(unlocked yes)
			(layer "F.Fab")
			(hide yes)
			(effects
				(font
					(size 1.016 1.016)
					(thickness 0.1524)
				)
			)
		)
		(property "Device Type" "C0201H13"
			(at -2.8321 -3.2639 90)
			(unlocked yes)
			(layer "F.Fab")
			(hide yes)
			(effects
				(font
					(size 1.016 1.016)
					(thickness 0.1524)
				)
			)
		)
		(duplicate_pad_numbers_are_jumpers no)
		(fp_rect
			(start -0.2794 0.6477)
			(end 0.2794 -0.6477)
			(stroke
				(width 0)
				(type default)
			)
			(fill no)
			(layer "F.CrtYd")
		)
		(fp_rect
			(start -0.2794 0.6477)
			(end 0.2794 -0.6477)
			(stroke
				(width 0)
				(type default)
			)
			(fill no)
			(layer "F.Fab")
		)
		(pad "1" smd custom
			(at 0 -0.2794 90)
			(size 0.0762 0.0762)
			(layers "F.Cu" "F.Mask" "F.Paste")
			(net "SAS_HDD_RX_P14")
			(options
				(clearance outline)
				(anchor circle)
			)
			(primitives
				(gr_poly
					(pts
						(arc
							(start 0.1524 -0.127)
							(mid 0.137521 -0.162921)
							(end 0.1016 -0.1778)
						)
						(arc
							(start -0.1016 -0.1778)
							(mid -0.137521 -0.162921)
							(end -0.1524 -0.127)
						)
						(arc
							(start -0.1524 0.127)
							(mid -0.137521 0.162921)
							(end -0.1016 0.1778)
						)
						(arc
							(start 0.1016 0.1778)
							(mid 0.137521 0.162921)
							(end 0.1524 0.127)
						)
					)
					(width 0)
					(fill yes)
				)
			)
		)
		(pad "2" smd custom
			(at 0 0.2794 90)
			(size 0.0762 0.0762)
			(layers "F.Cu" "F.Mask" "F.Paste")
			(net "PHY_SCC_A_TO_DRV_A_14_DP")
			(options
				(clearance outline)
				(anchor circle)
			)
			(primitives
				(gr_poly
					(pts
						(arc
							(start 0.1524 -0.127)
							(mid 0.137521 -0.162921)
							(end 0.1016 -0.1778)
						)
						(arc
							(start -0.1016 -0.1778)
							(mid -0.137521 -0.162921)
							(end -0.1524 -0.127)
						)
						(arc
							(start -0.1524 0.127)
							(mid -0.137521 0.162921)
							(end -0.1016 0.1778)
						)
						(arc
							(start 0.1016 0.1778)
							(mid 0.137521 0.162921)
							(end 0.1524 0.127)
						)
					)
					(width 0)
					(fill yes)
				)
			)
		)
	)
	(footprint ""
		(layer "F.Cu")
		(at 356.289102 -277.750016 -90)
		(property "Reference" "VIA18"
			(at 0 0 270)
			(layer "F.SilkS")
			(hide yes)
			(effects
				(font
					(size 1.27 1.27)
				)
			)
		)
		(property "Value" "100OHM-8L-1D6MM-L18L16-GP"
			(at -3.7211 -4.5085 270)
			(unlocked yes)
			(layer "F.Fab")
			(hide yes)
			(effects
				(font
					(size 1.016 1.016)
					(thickness 0.1524)
				)
			)
		)
		(property "Device Type" "VIA-PCIE-4P-394076"
			(at -3.7211 -6.0325 270)
			(unlocked yes)
			(layer "F.Fab")
			(hide yes)
			(effects
				(font
					(size 1.016 1.016)
					(thickness 0.1524)
				)
			)
		)
		(duplicate_pad_numbers_are_jumpers no)
		(fp_rect
			(start -1.9685 0.381)
			(end 1.9685 -0.381)
			(stroke
				(width 0)
				(type default)
			)
			(fill no)
			(layer "F.CrtYd")
		)
		(fp_rect
			(start -1.9685 0.381)
			(end 1.9685 -0.381)
			(stroke
				(width 0)
				(type default)
			)
			(fill no)
			(layer "F.Fab")
		)
		(pad "1" thru_hole circle
			(at -1.5875 0 270)
			(size 0.508 0.508)
			(drill 0.254)
			(layers "*.Cu" "*.Mask")
			(remove_unused_layers no)
			(net "GND")
			(clearance 0.127)
			(thermal_gap 0.127)
		)
		(pad "2" thru_hole circle
			(at -0.5715 0 270)
			(size 0.508 0.508)
			(drill 0.254)
			(layers "*.Cu" "*.Mask")
			(remove_unused_layers no)
			(net "PHY_DRV_A_TO_SCC_A_7_DP")
			(clearance 0.127)
			(thermal_gap 0.127)
		)
		(pad "3" thru_hole circle
			(at 0.5715 0 270)
			(size 0.508 0.508)
			(drill 0.254)
			(layers "*.Cu" "*.Mask")
			(remove_unused_layers no)
			(net "PHY_DRV_A_TO_SCC_A_7_DN")
			(clearance 0.127)
			(thermal_gap 0.127)
		)
		(pad "4" thru_hole circle
			(at 1.5875 0 270)
			(size 0.508 0.508)
			(drill 0.254)
			(layers "*.Cu" "*.Mask")
			(remove_unused_layers no)
			(net "GND")
			(clearance 0.127)
			(thermal_gap 0.127)
		)
	)
	(footprint ""
		(layer "F.Cu")
		(at 143.024098 -283.126942 -90)
		(property "Reference" "C100"
			(at 0 0 270)
			(layer "F.SilkS")
			(hide yes)
			(effects
				(font
					(size 1.27 1.27)
				)
			)
		)
		(property "Value" "SCD033U25V2KX-GP"
			(at 1.1811 -2.7051 270)
			(unlocked yes)
			(layer "F.Fab")
			(hide yes)
			(effects
				(font
					(size 1.016 1.016)
					(thickness 0.1524)
				)
			)
		)
		(property "Device Type" "C402H22"
			(at 1.1811 -4.2291 270)
			(unlocked yes)
			(layer "F.Fab")
			(hide yes)
			(effects
				(font
					(size 1.016 1.016)
					(thickness 0.1524)
				)
			)
		)
		(duplicate_pad_numbers_are_jumpers no)
		(fp_rect
			(start -0.4318 0.9525)
			(end 0.4318 -0.9525)
			(stroke
				(width 0)
				(type default)
			)
			(fill no)
			(layer "F.CrtYd")
		)
		(fp_rect
			(start -0.4318 0.9525)
			(end 0.4318 -0.9525)
			(stroke
				(width 0)
				(type default)
			)
			(fill no)
			(layer "F.Fab")
		)
		(pad "1" smd custom
			(at 0 -0.4445 270)
			(size 0.1524 0.1524)
			(layers "F.Cu" "F.Mask" "F.Paste")
			(net "SW_HDD_P4")
			(options
				(clearance outline)
				(anchor circle)
			)
			(primitives
				(gr_poly
					(pts
						(arc
							(start 0.3048 -0.2032)
							(mid 0.275042 -0.275042)
							(end 0.2032 -0.3048)
						)
						(arc
							(start -0.2032 -0.3048)
							(mid -0.275042 -0.275042)
							(end -0.3048 -0.2032)
						)
						(arc
							(start -0.3048 0.2032)
							(mid -0.275042 0.275042)
							(end -0.2032 0.3048)
						)
						(arc
							(start 0.2032 0.3048)
							(mid 0.275042 0.275042)
							(end 0.3048 0.2032)
						)
					)
					(width 0)
					(fill yes)
				)
			)
		)
		(pad "2" smd custom
			(at 0 0.4445 270)
			(size 0.1524 0.1524)
			(layers "F.Cu" "F.Mask" "F.Paste")
			(net "GND")
			(options
				(clearance outline)
				(anchor circle)
			)
			(primitives
				(gr_poly
					(pts
						(arc
							(start 0.3048 -0.2032)
							(mid 0.275042 -0.275042)
							(end 0.2032 -0.3048)
						)
						(arc
							(start -0.2032 -0.3048)
							(mid -0.275042 -0.275042)
							(end -0.3048 -0.2032)
						)
						(arc
							(start -0.3048 0.2032)
							(mid -0.275042 0.275042)
							(end -0.2032 0.3048)
						)
						(arc
							(start 0.2032 0.3048)
							(mid 0.275042 0.275042)
							(end 0.3048 0.2032)
						)
					)
					(width 0)
					(fill yes)
				)
			)
		)
	)
	(footprint ""
		(layer "F.Cu")
		(at 221.032832 -387.02488 -90)
		(property "Reference" "R130"
			(at 0 0 270)
			(layer "F.SilkS")
			(hide yes)
			(effects
				(font
					(size 1.27 1.27)
				)
			)
		)
		(property "Value" "10KR2F-2-GP"
			(at 0.064008 -3.993896 270)
			(unlocked yes)
			(layer "F.Fab")
			(hide yes)
			(effects
				(font
					(size 1.016 1.016)
					(thickness 0.1524)
				)
			)
		)
		(property "Device Type" "R402H16"
			(at 0.064008 -5.517896 270)
			(unlocked yes)
			(layer "F.Fab")
			(hide yes)
			(effects
				(font
					(size 1.016 1.016)
					(thickness 0.1524)
				)
			)
		)
		(duplicate_pad_numbers_are_jumpers no)
		(fp_line
			(start -0.508 -0.9398)
			(end -0.508 0.9398)
			(stroke
				(width 0.1524)
				(type default)
			)
			(layer "F.SilkS")
		)
		(fp_line
			(start 0.508 -0.9398)
			(end -0.508 -0.9398)
			(stroke
				(width 0.1524)
				(type default)
			)
			(layer "F.SilkS")
		)
		(fp_rect
			(start -0.508 0.9398)
			(end 0.508 -0.9398)
			(stroke
				(width 0)
				(type default)
			)
			(fill no)
			(layer "F.CrtYd")
		)
		(fp_rect
			(start -0.508 0.9398)
			(end 0.508 -0.9398)
			(stroke
				(width 0)
				(type default)
			)
			(fill no)
			(layer "F.Fab")
		)
		(pad "1" smd custom
			(at 0 -0.4445 270)
			(size 0.1397 0.1397)
			(layers "F.Cu" "F.Mask" "F.Paste")
			(net "P12V_A")
			(options
				(clearance outline)
				(anchor circle)
			)
			(primitives
				(gr_poly
					(pts
						(arc
							(start -0.1778 -0.2794)
							(mid -0.249642 -0.249642)
							(end -0.2794 -0.1778)
						)
						(arc
							(start -0.2794 0.1778)
							(mid -0.249642 0.249642)
							(end -0.1778 0.2794)
						)
						(arc
							(start 0.1778 0.2794)
							(mid 0.249642 0.249642)
							(end 0.2794 0.1778)
						)
						(arc
							(start 0.2794 -0.1778)
							(mid 0.249642 -0.249642)
							(end 0.1778 -0.2794)
						)
					)
					(width 0)
					(fill yes)
				)
			)
		)
		(pad "2" smd custom
			(at 0 0.4445 270)
			(size 0.1397 0.1397)
			(layers "F.Cu" "F.Mask" "F.Paste")
			(net "SCC_A_FULL_PWR_EN_12V")
			(options
				(clearance outline)
				(anchor circle)
			)
			(primitives
				(gr_poly
					(pts
						(arc
							(start -0.1778 -0.2794)
							(mid -0.249642 -0.249642)
							(end -0.2794 -0.1778)
						)
						(arc
							(start -0.2794 0.1778)
							(mid -0.249642 0.249642)
							(end -0.1778 0.2794)
						)
						(arc
							(start 0.1778 0.2794)
							(mid 0.249642 0.249642)
							(end 0.2794 0.1778)
						)
						(arc
							(start 0.2794 -0.1778)
							(mid 0.249642 -0.249642)
							(end 0.1778 -0.2794)
						)
					)
					(width 0)
					(fill yes)
				)
			)
		)
	)
)
